 
 
Open CloudServer OCS 
Chassis Specification 
Version 2.0 
 
 
 
 
 
Author: 
Mark Shaw, Director of Hardware Engineering, Microsoft 
 



Open Compute Project  Open CloudServer OCS Chassis 
http://opencompute.org ii 
Revision History 
Date Description 
10/30/2014 Version 2.0 
 
  



Open Compute Project  Open CloudServer OCS Chassis 
http://opencompute.org iii 
 
© 2014 Microsoft Corporation. 
As of October 30, 2014, the following persons or entities have made this Specification available under the Open Web 
Foundation Final Specification Agreement (OWFa 1.0), which is available at http://www.openwebfoundation.org/legal/the-owf-
1-0-agreements/owfa-1-0 
Microsoft Corporation.  
You can review the signed copies of the Open Web Foundation Agreement Version 1.0 for this Specification at 
http://opencompute.org/licensing/, which may also include additional parties to those listed above. 
Your use of this Specification may be subject to other third party rights. THIS SPECIFICATION IS PROVIDED "AS IS." The 
contributors expressly disclaim any warranties (express, implied, or otherwise), including implied warranties of merchantability, 
noninfringement, fitness for a particular purpose, or title, related to the Specification. The entire risk as to implementing or 
otherwise using the Specification is assumed by the Specification implementer and user. IN NO EVENT WILL ANY PARTY BE 
LIABLE TO ANY OTHER PARTY FOR LOST PROFITS OR ANY FORM OF INDIRECT, SPECIAL, INCIDENTAL, OR CONSEQUENTIAL 
DAMAGES OF ANY CHARACTER FROM ANY CAUSES OF ACTION OF ANY KIND WITH RESPECT TO THIS SPECIFICATION OR ITS 
GOVERNING AGREEMENT, WHETHER BASED ON BREACH OF CONTRACT, TORT (INCLUDING NEGLIGENCE), OR OTHERWISE, AND 
WHETHER OR NOT THE OTHER PARTY HAS BEEN ADVISED OF THE POSSIBILITY OF SUCH DAMAGE. 
CONTRIBUTORS AND LICENSORS OF THIS SPECIFICATION MAY HAVE MENTIONED CERTAIN TECHNOLOGIES THAT ARE MERELY 
REFERENCED WITHIN THIS SPECIFICATION AND NOT LICENSED UNDER THE OWF CLA OR OWFa. THE FOLLOWING IS A LIST OF 
MERELY REFERENCED TECHNOLOGY: INTELLIGENT PLATFORM MANAGEMENT INTERFACE (IPMI), I2C TRADEMARK OF PHILLIPS 
SEMICONDUCTOR. IMPLEMENTATION OF THESE TECHNOLOGIES MAY BE SUBJECT TO THEIR OWN LEGAL TERMS.  



 
iv October 30, 2014 
 
 
Contents 
1 Overview of V2.0 Open CloudServer Specifications ....................................................................................... 1 
2 Introduction to the Open CloudServer System .............................................................................................. 1 
3 Chassis Specification ...................................................................................................................................... 3 
3.1 Chassis Physical Specification ....................................................................................................................... 3 
3.1.1 Volumetric Specification .......................................................................................................................... 4 
3.1.2 Latching Features and Fasteners ............................................................................................................. 6 
3.1.3 Power Distribution Unit Placement ......................................................................................................... 7 
3.2 Power Delivery ............................................................................................................................................. 8 
3.3 Power Distribution Backplane ...................................................................................................................... 8 
3.4 Tray Specifications...................................................................................................................................... 10 
3.4.1 Volumetric Specifications ...................................................................................................................... 10 
3.4.2 Guiding and Latching ............................................................................................................................. 14 
3.5 Tray Interconnect ....................................................................................................................................... 14 
4 Cooling System Specifications ..................................................................................................................... 16 
4.1 Thermal Design Considerations .................................................................................................................. 16 
4.2 Airflow and Thermal Requirements............................................................................................................ 16 
4.3 Fan Speed Control ...................................................................................................................................... 18 
4.3.1 Pulse-Width Modulation Input .............................................................................................................. 18 
4.3.2 Fan Speed Correction for Altitude ......................................................................................................... 19 
4.3.3 Fan Speed Correction for Fan Failures ................................................................................................... 20 
4.3.4 Sensor Failure ........................................................................................................................................ 20 
4.4 Fan Failure .................................................................................................................................................. 21 
4.4.1 Fan Failure Rate ..................................................................................................................................... 21 
4.4.2 Fan Repair .............................................................................................................................................. 21 
4.5 Thermal Considerations for the Blade ........................................................................................................ 22 
5 Systems Management ................................................................................................................................. 22 
5.1 Systems Management Connectivity ........................................................................................................... 23 
5.2 Chassis Manager Specifications ................................................................................................................. 23 
5.2.1 Communication Ports ............................................................................................................................ 25 
5.2.2 Power Control ........................................................................................................................................ 26 
5.2.3 Chassis Manager Software and Programming Model ........................................................................... 27 
5.2.4 Blade Numbering ................................................................................................................................... 27 
5.2.5 Chassis LEDs ........................................................................................................................................... 28 
6 Tray Backplane Specification ....................................................................................................................... 29 
6.1 Tray Backplane Overview ........................................................................................................................... 29 



Open Compute Project  Open CloudServer OCS Chassis 
http://opencompute.org v 
 
6.2 12V Power Distribution .............................................................................................................................. 30 
6.3 SAS Channels .............................................................................................................................................. 31 
6.4 10 Gb/40Gb Ethernet ................................................................................................................................. 31 
6.5 Tray Mezzanine Card .................................................................................................................................. 32 
6.5.1 Chassis Management ............................................................................................................................. 33 
6.5.2 Guide Pins .............................................................................................................................................. 34 
6.6 Connector Pinouts and Signal Descriptions ................................................................................................ 34 
6.6.1 PDB 12V Power Connector .................................................................................................................... 35 
6.6.2 Blade 12V Power Connector .................................................................................................................. 36 
6.6.3 Blade SAS Interface ................................................................................................................................ 37 
6.6.4 Mini-SAS HD Connector ......................................................................................................................... 38 
6.6.5 Blade 10Gb Ethernet Connector ............................................................................................................ 40 
6.6.6 10GbE SFP+ Connector .......................................................................................................................... 41 
6.6.7 40GbE QSFP+ Connector ........................................................................................................................ 42 
6.6.8 Blade PCIe Gen3 Connector ................................................................................................................... 44 
6.6.9 Tray Mezzanine Card Connector ............................................................................................................ 47 
6.7 12V Power Cable ........................................................................................................................................ 49 
6.8 USB Cable ................................................................................................................................................... 50 
6.9 Connector Part Number Summary ............................................................................................................. 50 
6.10 Board Stackup ............................................................................................................................................ 51 
6.11 Tray Backplane Electrical Specifications..................................................................................................... 53 
6.11.1 Input Voltage, Power, and Current.................................................................................................... 53 
6.11.2 Grounding and Return ....................................................................................................................... 54 
6.12 Component and Hole Locations ................................................................................................................. 54 
  



 
vi October 30, 2014 
 
 
 
Table of Figures 
Figure 1: View of OCS with rack .................................................................................................................... 2 
Figure 2: Second view of OCS........................................................................................................................ 2 
Figure 3: V2.0 OCS blade ............................................................................................................................... 3 
Figure 4: Chassis details, rear ........................................................................................................................ 4 
Figure 5: Chassis details, from the front ....................................................................................................... 4 
Figure 6: V2.0 OCS chassis volumetric requirements (PDU volume is not shown) ...................................... 5 
Figure 7: Rear rack column seal .................................................................................................................... 6 
Figure 8: Column air flow passage ................................................................................................................ 6 
Figure 9: PDU placement .............................................................................................................................. 7 
Figure 10: PDU mounting strip ...................................................................................................................... 8 
Figure 11: Power distribution board ............................................................................................................. 9 
Figure 12: Example of a chassis/tray arrangement .................................................................................... 10 
Figure 13: Tray detail .................................................................................................................................. 11 
Figure 14: Interior tray opening chassis volumetric ................................................................................... 12 
Figure 15: Interior tray opening volumetric detail ..................................................................................... 13 
Figure 16: Side view of chassis .................................................................................................................... 13 
Figure 17: View of the push to release the spring latch ............................................................................. 14 
Figure 18: Power connector pin out ........................................................................................................... 15 
Figure 19: Fan tray (includes six 140 x 140 mm fans in parallel) ................................................................ 17 
Figure 20: Single fan airflow chart .............................................................................................................. 17 
Figure 21: Maximum allowable impedance curve for a single blade ......................................................... 18 
Figure 22: Example of altitude correction factor ........................................................................................ 20 
Figure 23: Tray and blade management connectivity ................................................................................ 23 
Figure 24: Chassis Manager block diagram ................................................................................................. 24 
Figure 25: Chassis Manager hardware block diagram ................................................................................ 25 
Figure 26: V2.0 OCS tray backplane block diagram .................................................................................... 29 
Figure 27: 12V power distribution .............................................................................................................. 30 
Figure 28: SAS block diagram ...................................................................................................................... 31 
Figure 29: Ethernet block diagram .............................................................................................................. 32 
Figure 30: Tray mezzanine card block diagram .......................................................................................... 33 
Figure 31: Management block diagram ...................................................................................................... 34 
Figure 32: Front view of header pins .......................................................................................................... 37 
Figure 33: Component and hole locations .................................................................................................. 54 
  



Open Compute Project  Open CloudServer OCS Chassis 
http://opencompute.org vii 
 
Table of Tables 
Table 1: List of specifications ........................................................................................................................ 1 
Table 2: Pinout for signal portion of power connector on tray backplane ................................................. 15 
Table 3: Pinout for power connector .......................................................................................................... 15 
Table 4: Fan control variables ..................................................................................................................... 19 
Table 5: Serial RJ-45 cable definition for port 1 and port 2 ........................................................................ 26 
Table 6: Serial RJ-45 cable definition for port 5 and port 5 ........................................................................ 26 
Table 7: Blade numbers .............................................................................................................................. 27 
Table 8: Chassis health status LED description ........................................................................................... 28 
Table 9: Chassis attention LED description ................................................................................................. 29 
Table 10: PDB 12V power connector pinout ............................................................................................... 35 
Table 11: PDB 12V power connector signal descriptions ........................................................................... 35 
Table 12: Blade 12V power connector pinout ............................................................................................ 36 
Table 13: AirMax Power connector header pinout .................................................................................... 37 
Table 14: Blade SAS interface connector pinout ........................................................................................ 38 
Table 15: SAS connector signal description ................................................................................................ 38 
Table 16: Mini-SAS HD connector pinout ................................................................................................... 39 
Table 17: Blade 10GbE connector pinout ................................................................................................... 40 
Table 18: Blade 10GbE signal definitions .................................................................................................... 40 
Table 19: 10GbE SFP+ connector pinout ..................................................................................................... 42 
Table 20: 40GbE QSFP+ connector pinout .................................................................................................. 43 
Table 21. PCIe interface connector pinout ................................................................................................. 45 
Table 22: PCIe Gen3 connector signal definitions ...................................................................................... 46 
Table 23: Tray mezzanine card connector pinout....................................................................................... 48 
Table 24: Tray mezzanine card signal definitions ....................................................................................... 49 
Table 25: USB pinout ................................................................................................................................... 50 
Table 26: Summary of connector part numbers ......................................................................................... 50 
Table 27: Recommended stackup for tray backplane ................................................................................ 51 
Table 28: Required impedance and recommended trace widths .............................................................. 52 
Table 29: Input voltage and current from the PDB ..................................................................................... 53 
Table 30: Output voltage and current to blades ......................................................................................... 53 
Table 31: Input voltage and current from blade to tray mezzanine card ................................................... 53 




Open Compute Project  Open CloudServer Chassis 
 
http://opencompute.org 1 
1 Overview of V2.0 Open CloudServer Specifications 
Table 1 lists the Open CloudServer (OCS) system specifications. 
Table 1: List of specifications 
Specification title Description 
Open CloudServer Chassis 
Specification Version 2.0 
Describes the hardware used in the Version 2.0 (V2.0) OCS 
system, including the chassis, tray, and systems management. 
Open CloudServer Blade 
Specification Version 2.0 
Describes the blade used in the V2.0 OCS system, including 
interconnect and blade hardware and blade management. 
Open CloudServer Tray Mezzanine 
Specification Version 2.0  
Describes the tray mezzanine card used in the V2.0 OCS system, 
including interconnect, hardware, and management. 
Open CloudServer NIC Mezzanine 
Specification Version 2.0  
Describes the Network Interface Controller (NIC) mezzanine card 
used in the V2.0 OCS system. 
Open CloudServer Chassis 
Management Specification Version 
2.0 
Describes the chassis manager command-line interface (CLI). 
This document is intended for designers and engineers who will be building chassis for an OCS 
system. 
2 Introduction to the Open CloudServer System 
The V2.0 OCS system is a fully integrated rack of servers and IT equipment that is highly optimized 
and streamlined for large, web-scale deployments.  
OCS is an off-the-shelf (OTS) commodity rack that is loaded with up to four modular chassis, each 
with trays, power supplies, power distribution, rack management, system fans, and two side-walls, 
as shown in Figure 1 and Figure 2. 



 
2 October 30, 2014 
 
 
Figure 1: View of OCS with rack  
 
Figure 2: Second view of OCS 
OCS blades are highly configurable, and are usually compute blades or storage “just a bunch of 
disks” (JBOD) blades.  
Figure 3 shows an example of a V2.0 OCS blade. 


Open Compute Project  Open CloudServer OCS Chassis 
http://opencompute.org 3 
 
 
Figure 3: V2.0 OCS blade 
Each chassis supports 12 rack unit (EIA 310-E standard U or 1U, each 17.7" wide and 1.75" tall) trays 
that house up to 24 individual OCS blades (two blades per tray). Blades can be designed to use the 
full width of the tray. It is also possible to use multiple rack units to house a single tall blade, with 
certain restrictions. 
Power, management, and networking are delivered through the tray backplane (TB) and the power 
distribution backplane (PDB). The tray backplane is located at the back of each tray. The power 
distribution backplane attaches vertically to the individual trays on one side and to the power 
supply unit (PSU) on the other side. This arrangement reduces the current carrying requirements of 
the distribution board, eliminates cabling, and reduces costs.  
Power and management signals are received from the PDB and distributed to the blades by 
Ethernet networking cables that pass through a blind-mate connector and are routed to 
attachments at the rear of the chassis. Note that running the cables through the rear of the blade 
eliminates the need to connect directly to the servers. Once provisioned, the network cabling 
should only be touched when a cable or switch fails or the typology is changed. The type and 
number of networking switches depends on the specific deployment. 
3 Chassis Specification 
The following sections describe the OCS chassis. 
The chassis is an assembly of supporting components designed to be individually mounted to the 
rack. It provides structure and airflow to the blades and other electrical subsystems 
3.1 Chassis Physical Specification 
The physical specifications for the chassis include the dimensions and a description of the guiding 
and latching features. 


 
4 October 30, 2014 
 
3.1.1 Volumetric Specification 
Figure 4 shows details of the chassis from the rear. Figure 5 shows details of the chassis from the 
front. 
 
Figure 4: Chassis details, rear 
 
Figure 5: Chassis details, from the front 


Open Compute Project  Open CloudServer OCS Chassis 
http://opencompute.org 5 
 
The chassis is enclosed at the top and bottom of the rear airflow plenum to minimize recirculation 
and maximize blade cooling. The top of the chassis is also enclosed to ensure that air passes 
through the blades. Note that airflow blanks are required for slots that are not occupied by blades. 
These blanks must be closed to airflow to avoid short-circuiting the adjacent blades. 
Figure 6 shows the chassis dimensions.  
 
Figure 6: V2.0 OCS chassis volumetric requirements (PDU volume is not shown) 
There is a separate inlet air plenum for the power supplies routed along the “Zero U” space of the 
rack. Features in the side plenum help seal this inlet when the chassis is secured in the rack so that 
the air from the hot aisle cannot enter the power supplies, as shown in Figure 7. 


 
6 October 30, 2014 
 
 
Figure 7: Rear rack column seal 
The chassis can accommodate a rack column spacing of 736.6mm. The columns must use 9.5mm 
square holes. Air for the power supplies is drawn through the columns, as shown in Figure 8. 
 
Figure 8: Column air flow passage 
Sliding sub-assemblies are keyed to ensure that they are connected correctly unless incorrect 
installation causes no damage. For example, the trays and blades are keyed so they will not be 
installed upside down; power supplies are not keyed because they cause no damage if installed 
upside down. 
Note that if the blades will be shipped within the chassis, additional braces are required for 
support. The braces transfer forces directly to the rack columns and provide load-bearing support 
for the front of the blades. 
Note also that the chassis is not intended to provide EMI containment. 
3.1.2 Latching Features and Fasteners 
Latches, as well as thumb screws and other components used to lock, unlock, or remove a 
subassembly from the chassis, are colored blue (Pantone code 285 C blue) to make them easy to 
identify.  


Open Compute Project  Open CloudServer OCS Chassis 
http://opencompute.org 7 
 
In the chassis, these latching features include: 
 Fan door securing features 
 Power supply unit latch covers 
 Chassis Manager module securing features 
To avoid confusion when removing a blade, the tray release wire form loops should not be colored 
blue. 
Fasteners that require Torx drivers can be used to secure the chassis to the rack. Assembling the 
trays, blades, power supplies, and the fan tray does not require tools. 
3.1.3 Power Distribution Unit Placement 
Figure 9 shows the location of the Power Distribution Unit (PDU) with respect to the chassis. The 
PDU mounting features are meant to wrap around the rack outer shell for clearance of a 1200mm 
long rack.  
 
Figure 9: PDU placement 
The chassis includes mounting key holes to secure the PDU in the correct position, as shown in 
Figure 10. The PDU has corresponding standoffs.  


 
8 October 30, 2014 
 
 
Figure 10: PDU mounting strip 
3.2 Power Delivery 
The chassis delivers power to the trays through the power distribution backplane. Using six PSUs on 
a shared power backplane provides nearly ideal phase balancing of three-phase AC inputs, which 
allows a higher utilization of the incoming power. 
Note that most of the weight of the power supplies is supported by the chassis, not by the power 
connector. 
3.3 Power Distribution Backplane 
The power distribution backplane (PDB) provides power to each tray assembly, to the fan assembly, 
and to the Chassis Manager card.  
The power distribution backplane also acts as the center point for chassis data communications, 
and includes the following cable connections: 
 LAN 1, 2 
 Serial COM 1, 2, 5, 6 
 Power control switch outputs 1, 2, 3 
 Chassis Manager power control input 
 Fan door power, control, and monitoring 


Open Compute Project  Open CloudServer OCS Chassis 
http://opencompute.org 9 
 
The power distribution backplane accepts 19 assemblies: 
 Chassis Manager 
 12 tray backplane connectors  
 6 power supply connectors 
Figure 11 shows details of the power distribution backplane. 
 
Figure 11: Power distribution board 


 
10 October 30, 2014 
 
3.4 Tray Specifications 
The sections that follow describe the V2.0 Open CloudServer trays.  
For service and debugging, the tray must be able to function in standalone mode (external to the 
chassis) for debugging. The tray can attach and receive power, Blade_EN, and serial signals without 
impacting cost or operation in production environments. The preferred method to attach to the 
tray is through headers that are not loaded for operation within the chassis. 
The physical specifications for the trays include the dimensions of the tray volume and a description 
of the guiding and latching features. 
3.4.1 Volumetric Specifications 
Figure 12 shows an example of a chassis/tray arrangement. Figure 13 provides mechanical feature 
details of the tray. 
 
Figure 12: Example of a chassis/tray arrangement 
 
Tray 
Chassis 
Bulk power 
Fan tray 



Open Compute Project  Open CloudServer OCS Chassis 
http://opencompute.org 11 
 
 
Figure 13: Tray detail 
The figures that follow describe the mechanical mating locations of the tray into the chassis. The 
tray’s outer dimensions must not exceed those described, with all tolerances for different 
manufacturing methods (such as soft and hard tooling) accounted for; the tray’s interior must be 
able to accept a blade as described in Section 3.1: Volumetric Specifications. The tray mechanically 
interlocks to the power backplane support to minimize the load the connector must support.  
The chassis is designed to be installed into a rack that complies with the EIA-310-D standard (the 
current revision of the Electronic Industries Alliance standard for a 19” rack) without modification.  
Figure 14 describes the opening in the chassis that accepts the trays, as viewed from the front of 
the system.  


 
12 October 30, 2014 
 
  
Figure 14: Interior tray opening chassis volumetric 
The chassis interior consists of a series of shelves that extend from the side walls to support the 
trays. The power distribution board is located at the rear of the opening, on the left side as viewed 
from the front, to transfer power from the bulk power supply units to the trays.  
Figure 15 shows the tray volume as seen from the front and defines the location of the tray 
supports as related to the power connector. A tray latch release is integrated into the chassis 
structure located on the left and right sides of the chassis opening.  


Open Compute Project  Open CloudServer OCS Chassis 
http://opencompute.org 13 
 
  
Figure 15: Interior tray opening volumetric detail 
Figure 16 shows a side view of the chassis. These dimensions are critical to the fit and function of 
the tray. 
 
Figure 16: Side view of chassis 
Notes:   
[1] Power connector surface end to hard 
stop on surface 
[2] Power connector surface end to tray 
load pin tip 
[3] Power connector surface end to tray 
latch holding surface 
 



 
14 October 30, 2014 
 
3.4.2 Guiding and Latching 
The chassis supports the tray on a series of shelves located on each side wall. These are designed 
and manufactured to prevent metallic slivers from forming when the tray is inserted into the 
chassis. Shoulder pins are included in the chassis side walls to secure the walls of the tray during 
insertion and prevent the tray from sagging under the load of the blades. 
A pull-to-release spring latch is incorporated into the left-side and right-side panels to keep the tray 
in the chassis. Figure 17shows a pull-to-release latch. Figure 16 shows the dimensions of the latch 
 
Figure 17: View of the push to release the spring latch 
3.5 Tray Interconnect 
The chassis provides electrical power and signaling to the tray.  
Figure 18 shows the recommend connectors.  


Open Compute Project  Open CloudServer OCS Chassis 
http://opencompute.org 15 
 
 
Figure 18: Power connector pin out 
The power connector supports a maximum of 1,382W per tray (12V x 16 pins x 9A/pin x 80 percent 
derating). The power per rack unit is limited to 600W. This connector allows a future 2U server to 
consume 1200W. 
Table 2 shows the pinout for the signal part of the power connector on the tray backplane 
Table 2: Pinout for signal portion of power connector on tray backplane 
Pin Signal name Tray input/output Definition 
S1 SERIAL_B1_TX1 Input Blade 1 serial input 1 
S2 SERIAL_B1_RX1  Output Blade 1 serial output 1 
S3 BLADE_B1_EN1 Input Blade 1 power enable 
S4 PSU_B1_ALERT_N Input Blade 1 PSU Alert 
S5 SERIAL_B1_TX2 Input Blade 1 serial input 2 
S6 SERIAL_B1_RX2 Output Blade 1 serial output 2 
S12 SERIAL_B2_TX1 Input Blade 2 serial input 1 
S11 SERIAL_B2_RX1  Output Blade 2 serial output 1 
S10 BLADE_B2_EN1 Input Blade 2 power enable  
S9 PSU_B2_ALERT_N Input Blade 2 PSU Alert 
S8 SERIAL_B2_TX2 Input Blade 2 serial input 2 
S7 SERIAL_B2_RX2 Output Blade 2 serial output 2 
Table 3 shows the power connector pin-out. 
Table 3: Pinout for power connector 
Pin Signal name Capacity 
P1 through P4 12V return 9A per pin 
P5 through P8 12V return 9A per pin 
P9 through P12 12V supply 9A per pin 


 
16 October 30, 2014 
 
Pin Signal name Capacity 
P13 through P16 12V supply 9A per pin 
P17 through P20 12V supply 9A per pin 
P21 through P24 12V supply 9A per pin 
P25 through P28 12V return 9A per pin 
P29 through P32 12V return 9A per pin 
4 Cooling System Specifications 
The following sections describe the V2.0 Open CloudServer cooling system. 
Cooling for the blades is provided by six 140mm x 140mm shared rear-system fans mounted on the 
chassis. The fans are configured in an N+1 arrangement; if a fan fails, the system can maintain the 
required cooling with the remaining fans. 
Power supplies are cooled by their internal fans and supplied with fresh air by a channel along the 
side of the server. 
4.1 Thermal Design Considerations 
The fans provide all of the cooling and airflow required by the blades; it is therefore critical to 
design the blades so that all of their components are sufficiently cooled by the system fans. 
The V2.0 Open CloudServer cooling system was designed so that the fans consume the least 
amount of power possible while maintaining the necessary cooling.  
The blade server exhaust temperature directly reflects the hot-aisle temperature of a data center. 
4.2 Airflow and Thermal Requirements 
The chassis is intended to provide adequate airflow to the servers if the servers are designed to 
meet the following airflow requirements. Figure 19 shows the fan tray, and Figure 20 shows 
individual fan airflow curve of one manufacturer. 



Open Compute Project  Open CloudServer OCS Chassis 
http://opencompute.org 17 
 
 
Figure 19: Fan tray (includes six 140 x 140 mm fans in parallel) 
 
Figure 20: Single fan airflow chart  


 
18 October 30, 2014 
 
Figure 21 shows the maximum allowable impedance curve of single blade (in cubic foot per minute 
[CFM] versus inches of water [inH2O]. The target airflow is less than 31 CFM at full fan speed. 
 
Figure 21: Maximum allowable impedance curve for a single blade 
4.3 Fan Speed Control 
The fans have variable speed capability; this lets the system drive the fans at speeds only as high as 
necessary to cool the components, minimizing power consumption, noise, and fan failures. 
4.3.1 Pulse-Width Modulation Input 
The blades exchange thermal information with the Chassis Manager through an intelligent platform 
management interface (IPMI). The first sensor value in the IPMI table is the pulse-width modulation 
(PWM) duty cycle fan speed, a value between the non-critical limits of 0 (fan off) and 100 (fan 
running at full speed). Note that the minimum fan speed is 20 percent of duty cycle to ensure that 
the fan has enough torque to maintain rotation. 
Using PWM signals simplifies the system-level control strategy and allows the system to be blade 
agnostic. Blades request their own fan speeds. The Chassis Manager polls each blade periodically 
for its fan flow rate request through a PWM signal, and then drives the fan speeds based on the 
highest request.  
Blades are responsible for monitoring all thermally critical component temperatures and 
determining an appropriate fan speed. A closed-loop method for monitoring temperature and 
adjusting speed requests is highly recommended. At minimum, a fan speed table based on 
measured inlet temperature is required, and the inlet and outlet temperatures of thermally critical 
components (such as processors, DIMMs, and PCHs) should be available through the IPMI interface. 
These sensors should have identification values other than 1 and should not have metadata limits.  


Open Compute Project  Open CloudServer OCS Chassis 
http://opencompute.org 19 
 
Table 4 lists important variables in fan control strategy. 
Table 4: Fan control variables 
Variable Value and description 
Target temperature band 
Used to control limits of processor temperature 
Upper = target temperature 
Lower = target temperature – 4OC 
Blade poll frequency Frequency of blade temperature requests 
10 seconds 
Fan speed decrease hysteresis 
The amount of time the fan must wait between speed changes (prevents 
the fan speed from rising and falling too frequently) 
1 minute 
Altitude compensation Increase speed by 3.2 percent for every 1000 ft (304m) above sea level (see 
Figure 20) 
Active fan correction factor 
𝐷𝐶 = 𝐷𝐶𝑏𝑎𝑠𝑒 ∗ (5 𝑁𝑎𝑐𝑡𝑖𝑣𝑒⁄ ) 
𝐷𝐶 is the fan speed duty cycle requested by the Chassis Manager 
𝐷𝐶𝑏𝑎𝑠𝑒 is the base fan speed duty cycle before fan count and 
altitude correction 
𝑁𝑎𝑐𝑡𝑖𝑣𝑒 is the number of active system fans (if no fans have failed, 
this is six) 
4.3.2 Fan Speed Correction for Altitude 
In blades that choose to operate fan speed based on inlet temperature readings, fan speed must be 
increased by 3.2 percent for every 1000 ft (304 m) above sea level. The location of the system must 
therefore be recorded during installation so that the correction can be made. 
Figure 22 shows an example of fan speed correction for altitude with the following non-critical 
limits:  
 Lower = 15⁰C ambient 
 Upper = 35⁰C ambient 



 
20 October 30, 2014 
 
 
Figure 22: Example of altitude correction factor  
4.3.3 Fan Speed Correction for Fan Failures 
The Chassis Manager monitors the number of active fans and makes appropriate adjustments to 
the fan speed if a fan is detected to have failed (Section 4.4: Fan Failure provides more information 
about fan failure). A fan is considered to have failed if the tachometer speed returned to the 
Chassis Manager is below 25 percent of the requested speed for more than five minutes. 
Note that fan failures trigger an alert so that the fan can be replaced (no action is required on the 
blade). 
4.3.4 Sensor Failure 
If a PWM signal from a specific blade is not detected or is determined to be unrealistic (less than 0 
or more than 100), the blade is assigned a request of the minimum fan speed, and the speed 
requests from the other blades in the system will take priority.  
If there is only one blade is in the system and if the PWM signal is not present, the chassis will 
operate fans at the minimum speed. If blade activity forces a thermal shut-down under these 
conditions, the blade must be replaced or repaired.  
If the blades in the chassis are plugged in but are in standby mode, the Chassis Manager will drive 
fan speed at the minimum level. 


Open Compute Project  Open CloudServer OCS Chassis 
http://opencompute.org 21 
 
4.4 Fan Failure 
Analysis shows that fan failures (tachometer speed below 25 percent of the requested speed for 
more than five minutes) are rare. 
4.4.1 Fan Failure Rate 
Failure rate for the fans is calculated using the following information: 
 Mean time between failures (MTBF) provided by the manufacturer is 50K hours at 60⁰C. 
 Failure rate improves two times for every 10⁰C reduction. 
 Average outlet operating temperature is approximately 46⁰C, allowing for a greater than two 
times reduction. 
 Annualized failure rate is therefore: 
o 6x10E-6 per chassis 
o 2.4x10E-5 per rack 
 Failures per year are therefore: 
o 0.05 for a chassis (one failure every 20 years) 
o 0.20 for a rack (one failure every 5 years) 
Data from the server vendor indicates that the most common cause of fan failure is a lubricant leak, 
which causes a fan to speed up for approximately a week before stopping when the lubricant is 
gone. Chassis management can monitor the speed of the fans and identify an algorithm to address 
speeds that are too fast or too slow. When a fan failure is detected, chassis management will speed 
up the remaining fans to compensate. 
4.4.2 Fan Repair 
If fan repair does become necessary, the fan tray assembly is mounted on a pinned hinge so that 
the full tray can be easily removed for repair, and both sides of the fans have wire screen guards for 
safety during service. 
The following steps describe how to replace a fan: 
1. Prepare all materials and a ladder if the fan is in the upper half of the rack. 
2. Open the fan door and disconnect the cable. 
3. Lift the fan tray off the hinge. 
4. Install the new fan tray onto the hinge. 
5. Plug in the cable. 
6. Close the fan door. 



 
22 October 30, 2014 
 
Note that if chassis management turned the chassis attention LED on because of the fan failure, it 
will turn the LED off when it detects that the fans are operating correctly. 
4.5 Thermal Considerations for the Blade 
The blade must be able to operate at full-load capacity in all conditions described in this 
specification, including the upper and lower ambient temperatures, humidity levels, altitude levels, 
and available fan capability. If conditions are outside the prescribed limits, the blade should 
continue to operate as long as hardware and data are not at risk; if conditions are likely to cause 
damage, the blade should be shut down.  
For the largest possible operating range, the inlet temperature to the system should not drive blade 
shut down. The temperature of sensitive components should be individually monitored to prevent 
an unnecessary system shut down. 
Note that blade components frequently have an average operating temperature target that 
optimizes long-term reliability and an upper temperature limit to prevent hardware damage and 
maintain data integrity. Components should normally operate at the target, but they can operate at 
a higher temperature for a short time as long as they remain below the upper limit. 
The only thermal response the Chassis Manager gives is control of fan speed. While alerts are 
logged if a fan or a blade fails, the Chassis Manager does not request blade shut downs. The blade 
is responsible for shut downs or throttling caused by high inlet temperature. 
5 Systems Management 
The following sections provide specifications for OCS systems management 
Systems management in OCS is designed to present a consistent, optimized interface. A Chassis 
Manager provides the front end through an applications interface (RESTful web API) for automated 
management and a command-line interface (CLI) for manual management (see Table 1 in Section 1 
for a list of available specifications). The Chassis Manager manages all devices within the rack and 
communicates directly with the blade management system through a serial multiplexor. 
Note that there are two possible paths for systems management in OCS: in-band and out-of-band 
(OOB).  
 The in-band management path is through the primary NIC while the operating system is 
running.  
  The out-of-band path is through the Chassis Manager.  
In-band is the preferred path for systems management whenever possible. 



Open Compute Project  Open CloudServer OCS Chassis 
http://opencompute.org 23 
 
5.1 Systems Management Connectivity 
Chassis management consists of a Chassis Manager module (the PCBA) that plugs into the power 
distribution backplane through a connector. This card is responsible for management and 
monitoring of the power supplies and fans, and makes it possible to keep active components off 
the power distribution and tray backplanes.  
A serial multiplexor (baud rate of 115200) lets the Chassis Manager distribute Blade_EN signals to 
the individual blades. The signals must be able to be modified so as to coordinate power cycling of 
multiple JBOD trays.  
Figure 23 shows management signals passed through the passive tray backplane to the blades. 
Chassis Manager
            Power Distribution
           Board
Tray Backplane
PDB Connector
TBP Connector (Goldfinger)
CPU
BLADE 2
CM Connector
PDB Connector
M
U
X
UART4 UART_T[1:12]_BLAD[1:4]
BLADE1
        PSU #1
        PSU #2
        PSU #3
        PSU #4
        PSU #5
        PSU #6
UART_T[1:12]_BLAD[1:4]
T[1:12]_PSU_
PSU_B2_ALERT_N
SERIAL_B2_TX/RX1
SERIAL_B2_TX/RX2
BMC
12V
HSCBLADE_B2_EN12V
BLADE2
AirMax VS2
12V
UART1
UART2
BLADE_EN
12V
COM1
COM3
Pcap
Logic PCH
PSU_ALERT_N
BLADE 1
BMC
12V
HSC
UART1
UART2
BLADE_EN
12V
COM1
COM3
Pcap
Logic PCH
PSU_ALERT_N
AirMax VS2
PSU_B1_ALERT_N
SERIAL_B1_TX/RX1
SERIAL_B1_TX/RX2
BLADE_B1_EN
12V
I2C_PSU[1:3]
I2C
GPIOs
UART
COM4
I2C
COM3
I2C_COM3
T[1:12]_NODE[1/3]_EN T[1:12]_NODE[1/3]_EN
ALERT_N
PSU[1:6]_OK_[AC/DC]
I2C
HUB
I2C
12V
OK_[AC/DC]
ALERT#
I2C
12V
OK_[AC/DC]
ALERT#
I2C
12V
OK_[AC/DC]
ALERT#
I2C
12V
OK_[AC/DC]
ALERT#
I2C
12V
OK_[AC/DC]
ALERT#
I2C
12V
OK_[AC/DC]
ALERT#
I2C_PSU3
I2C_PSU2
I2C_PSU1
I2C
GPIOs PSU_ALERT_N
FAN TRAY
FAN x 6
FAN CABLE
I2C
GPIOs
FAN_TACH[1:6]
12V
 
Figure 23: Tray and blade management connectivity 
5.2 Chassis Manager Specifications 
The Chassis Manager, a general purpose and highly flexible device, is located in the plenum of the 
chassis. 
Figure 24 shows a block diagram of the chassis, including the Chassis Manager, trays, power 
supplies, and fans.  



 
24 October 30, 2014 
 
 
Figure 24: Chassis Manager block diagram 
Following are specifications of the Chassis Manager: 
 Input/Output: 
o 2 x 1GbE Ethernet (general purpose to be used for network access or for direct 
connector to the top-of-rack management ports) 
o 4 x RS-232 (network switch management for boot strap initial start-up) 
 Windows Embedded operating system (enables a secure solution) 
 Embedded x86 processor 
 Hot repair, no downtime during replacement 
 Memory—4GB with error-correcting code (ECC) 
 Storage—8GB solid-state drive (SSD) 
 Power control—one input signal, three output signals to the PDU or to another Chassis Manager 
for remote power control 
 No Peripheral Component Interconnect (PCI) or PCI Express (PCIe) slot 
 USB and Video Graphics Array (VGA) support used for early debugging only, will be removed for 
production 
Figure 25 shows a detailed block diagram of the Chassis Manager.  
  
Chassis Management
General purpose and highly flexible
Chassis        
Fan Tray
PSUs
1 .. 6
Tray
1 .. 12
Chassis Manager
Win7 Embedded
Serial Fanout
Power Control
PSU Monitoring
Fan Control and 
Monitoring
2 x 1GbE
General 
Purpose
4 x RS232
NWK Switch 
Management
Power Control
3 x Outputs
1 x Input



Open Compute Project  Open CloudServer OCS Chassis 
http://opencompute.org 25 
 
 
Figure 25: Chassis Manager hardware block diagram 
5.2.1 Communication Ports 
Table 5 lists the definition and translation of the serial COM port signals of the RJ-45 connector for 
ports 1 and 2. These match the functionality of switch consoles that use RJ-45, but can be used to 
select cables that convert from DB-9 or DB-25 connections. The system swaps received 
data/transmitted data (RxD/TxD), clear to send/request to send (CTS/RTS), and data terminal 
ready/data set ready (DTR/DSR) signals so a straight Ethernet cable can be used. 
  Chassis Manager  (CM)
Tray1_Blade_EN[3:0]
Tray2_Blade_EN[3:0]
Tray3_Blade_EN[3:0]
Tray4_Blade_EN[3:0]
Fan PWM
CMC_Fan Tach[4:1]
Fan Ctl 
ADT7470
0x5Eh
6 PSU 6 PSU 6 PSU 6 PSU 6 PSU 6 Fans
Tray5_Blade_EN[3:0]
Tray6_Blade_EN[3:0]
Tray7_Blade_EN[3:0]
Tray8_Blade_EN[3:0]
Tray9_Blade_EN[3:0]
Tray10_Blade_EN[3:0]
Tray11_Blade_EN[3:0]
Tray12_Blade_EN[3:0]
PCA9535C
GPIO
0x40h
PCA9535C
GPIO
0x42h
PCA9535C
GPIO
0x44h
X86 PC
CM FRU EEPROM
0xA0h
Fan Ctl 
ADT7470
0x58h
CMC_Fan Tach[5:6]
CPLD_3
Altera
EPM240
1
2
…
23
24
          RST   RX/TX
Tray7_Node1_TX/RX
Tray7_Node2_TX/RX
Tray12_Node3_TX/RX
Tray12_Node4_TX/RX
PCA9535C
GPIO
0x48h
PCA9516
I2C Hub
PMBus1
6 PSU PSU 1..2
6 PSU PSU 3..4
6 PSU PSU 5..6
PMBus2
PMBus3
AC_OK[6:1]
DC_OK[6:1]
SC18IM700
(RS232 to I2C)
PMB_EN_1
PMB_EN_2
PMB_EN_3
PCA9535_INT_N
FAN_MAX_CTR
CPLD_WDT_1
CPU_RST_N
CMC_RESERVE_1
GPIO0
GPIO1
GPIO2
GPIO3
GPIO4
GPIO5
GPIO6
GPIO7
RST#          TX/RX
I2C
Attention LED
Status LEDPCA9535C
GPIO
0x4Ah
PSU_PS_ON[6:1]
TAKEOVER_ENABLE_N
PCA_CPLD_WDT2
Power Switch[2:0]
CPLD_FAN_MAX
CPLD_WDT[1,3]
TAKEOVER_ENABLE_N
WDT_ENABLE_N
UART_SW_S[0:5]_N
CMC_CPU_RST_N
CPLD_EXT_RST_N
CMC_RESERVE_1
FAN_MAX_CTR
CPLD_FAN_MAX
PMB_EN_[1:3]
CPLD_2
Altera
EPM240
1
2
…
23
24
RST   RX/TX                    .
Tray1_Node1_TX/RX
Tray1_Node2_TX/RX
Tray6_Node3_TX/RX
Tray6_Node4_TX/RX
WDT_LED
SC18IM700
(Serial Mux Ctlr)
UART_SW_S0_N
UART_SW_S1_N
UART_SW_S2_N
UART_SW_S3_N
UART_SW_S4_N
UART_SW_S5_N
WDT_EN_N (TBD)
CABLE_DETECT_N
GPIO0
GPIO1
GPIO2
GPIO3
GPIO4
GPIO5
GPIO6
GPIO7
RST#          TX/RX
I2C
COM3
RI
RTS
DTR
TX/RX
COM4
RI
RTS
DTR
TX/RX
PSU_ALERT_N
CPLD_THRMTRIP_LOG_N
PCA9535_INT_N
PDB FRU EEPROM
(not populated) 0xA2h
PDB
1GbE
RJ45
(metal)
COM1 
RJ45 
(plastic)
COM2 
RJ45 
(plastic)
COM5 
RJ45 
(plastic)
1GbE
RJ45
(metal)
RCOM5 
RJ45 
(de-pop)
RCOM6 
RJ45 
(de-pop)
COM6 
RJ45 
(plastic)
ON/OFF 
output
ON/OFF 
output
ON/OFF 
output
ON/OFF 
CM input



 
26 October 30, 2014 
 
Table 5: Serial RJ-45 cable definition for port 1 and port 2 
Signal on CM board RJ-45 connector pin RJ-45 connector pin Switch console port 
RTS 1 1 CTS 
DSR 2 2 DTR 
RxD 3 3 TxD 
GND 4 4 GND 
GND 5 5 GND 
TxD 6 6 RxD 
DTR 7 7 DSR 
CTS 8 8 RTS 
Table 6 lists the definition and translation of the serial COM port signals of the RJ-45 connector for 
serial COM ports 5 and 6. Note that COM port 3 and 4 are internal to the Chassis Manager board. 
Table 6: Serial RJ-45 cable definition for port 5 and port 5 
Signal on CM board RJ-45 connector pin RJ-45 connector pin Switch console port 
RTS 1 1 CTS 
DSR 2 2 DTR 
RxD 3 3 TxD 
RI 4 4 GND 
GND 5 5 GND 
TxD 6 6 RxD 
DTR 7 7 DSR 
CTS 8 8 RTS 
5.2.2 Power Control 
The Blade_EN signals let all servers on a single tray be powered on/off coincidently, and let servers 
on different trays be powered on/off either coincidently or through timed power control. 
Timed power control can be used to control servers and JBODs, (for example, to prevent incorrect 
errors from being reported when using a head server node and JBOD blades). The following steps 
can be used: 
1. Power off the head (server) node, and allow a short delay. 



Open Compute Project  Open CloudServer OCS Chassis 
http://opencompute.org 27 
 
2. Power off the JBOD blade, and allow a five second delay. 
3. Power on the JBOD blade, and allow a short delay.  
4. Power on the head (server) node. 
Timed delays can be easily adjusted to match the needs of the hardware and storage though the 
Chassis Manager. 
The Chassis Manager exports up to three 12V ON/OFF signals. The default is 0V (ON); 12V is OFF. 
The signals are sent to either relays on a PDU or to other Chassis Managers. 
5.2.3 Chassis Manager Software and Programming Model 
Microsoft will write the software that runs on the Chassis Manager, including software for 
monitoring and managing the power supplies, system fans, and Blade_EN signals. A vendor will 
write, document, and test a driver to interface to chassis management. Microsoft will provide the 
higher-level interface and API for attachment to the Chassis Manager. 
5.2.4 Blade Numbering 
Blades are hard wired through the management subsystem to specific positions. This ensures that 
there is zero ambiguity for service or networking. Table 7 lists the blade numbers, with both front 
and rear views. 
Table 7: Blade numbers 
U number Blades viewed from front Blades viewed from rear 
12 12 24 24 12 
11 11 23 23 11 
10 10 22 22 10 
9 9 21 21 9 
8 8 20 20 8 
7 7 19 19 7 
6 6 18 18 6 
5 5 17 17 5 
4 4 16 16 4 
3 3 15 15 3 
2 2 14 14 2 
1 1 13 13 1 



 
28 October 30, 2014 
 
5.2.5 Chassis LEDs 
Each chassis has two light-emitting diodes (LEDs) on the Chassis Manager: a health status LED that 
is green and an attention LED that is red. Both LEDs are driven by a single GPIO bit off the blade’s 
management i2c tree. 
5.2.5.1 Chassis Health Status LED 
The chassis health status LED indicates whether the Chassis Manager has booted. Note that if the 
12V power is off, the LEDs on the power supplies are also off. Table 8 describes the operation of the 
chassis health status LED. 
Table 8: Chassis health status LED description 
LED status Condition 
OFF 
 Backplane 12V power is OFF if power supply LEDs are OFF 
 Backplane 12V power is ON, but Chassis Manager never booted if power 
supply LEDs are ON  
Solid green ON  Backplane 12V power is ON and Chassis Manager has booted 
5.2.5.2 Chassis Attention LED 
The chassis attention LED is visible from the rear of the chassis without opening the fan tray. This 
LED directs service technicians to the correct chassis during repair. When possible, blade 
diagnostics are used to direct repairs; alternately, the Microsoft scale-out management software 
can be used. In both cases, logs of the repair work are available.  
The chassis attention LED indicates the following conditions: 
 Operator directed 
An operator can manually set the chassis attention LED (for example, identification of chassis 
cables). 
 Power supply failure 
Chassis Manager has detected a power supply failure. 
 Fan failure 
Chassis Manager has detected a fan failure. 
Note that the chassis attention LED must be turned off after service is complete. 
Table 9 describes the operation of the chassis attention LED 



Open Compute Project  Open CloudServer OCS Chassis 
http://opencompute.org 29 
 
Table 9: Chassis attention LED description 
LED status Condition 
OFF  No attention indicated 
Solid red ON  Operator directed 
 Power supply or fan failure 
6 Tray Backplane Specification 
The sections that follow describe the tray backplane. 
6.1 Tray Backplane Overview 
The tray backplane provides a connector backplane interface to two half-width blade Printed Circuit 
Assemblies (PCAs) or a single full-width blade PCA. The purpose of the tray backplane is to enable 
external connector and cable interfaces to the internal blade assemblies, as well as to pass 12V 
power from the PDU to the blade assemblies.  
Figure 26 shows the major interfaces between the blade assembly and the tray backplane 
assembly. The block diagram is not to scale, but is intended to communicate relative location of the 
components on the tray backplane. 
12V
12V
PDB
UART
SAS 
Mini
HD x4
B2P1
SAS
Airmax
VS2
3x6
SAS x4
Cables
10GbE
Airmax
VS2
3x6
10GbE
Cable
SAS
Mini
HD x4
B2P2
SAS
Mini
HD x4
B1P1
SAS
Airmax
VS2
3x6
PCIe
Airmax
VS85
5x10
SAS x4
Cables
SAS
Airmax
VS2
3x6
SEAF 8x20
SAS
Mini
HD x4
B1P2
Blade 2 Blade 1
PCIe x16
12Gb
SAS x8 P1  P2 PCIe x16
12Gb
SAS x8 12V
SEAF 8x20
PCIe
Airmax
VS85
5x10
40GbE
Cable
S
F
P
+
B1P2
10GbE
Cable
Q
S
F
P
+
B1P1
40GbE
Cable
EdgefingersTray
Backplane
P1  P2
P1 P2P1 P2
40GbE 10GbE 40GbE 10GbE
1
2
V
12V
1
2
VS
F
P
+
B2P2
Q
S
F
P
+
B2P1
U
S
B
U
S
B
 
Figure 26: V2.0 OCS tray backplane block diagram 



 
30 October 30, 2014 
 
6.2 12V Power Distribution 
The tray backplane will accept 12V originating from the PDU through the PDB, and will distribute 
the 12V to each of the two blade motherboards through AirMax power connectors. The tray 
backplane will support a maximum of 40A to each blade. The 12V will also be distributed to an 
optional Mini-Fit Jr.™ connector for cabling to separate assemblies, and will support a maximum of 
10A. 
A conditioned 12V is received by the tray backplane through the PCIe AirMax VS2 connector for 
distribution to the tray mezzanine card. The tray backplane will support a maximum of 3A to each 
tray mezzanine card.  
Figure 27 shows a block diagram of the 12V distribution.  
BLADE Motherboard
Tray
Backplane
Tray Mezz
BLADE_EN1
12V
Conditioned
12V Raw
3.3V
BLADE_MATED_N
3.3V GbE Airmax
VS2
Airmax
Power
Short Pin
Short Pin
Long Pin
MINI
FIT
PDB
Edge
Finger
PCIe Airmax
VS2
Hot
Swap
Controller
PCIe AirMax
VS2
Short Pin
Long Pin
BLADE_MATED_N
3.3V
Vin
En
UV
 
Figure 27: 12V power distribution 



Open Compute Project  Open CloudServer OCS Chassis 
http://opencompute.org 31 
 
6.3 SAS Channels 
The tray backplane will support a 12Gb Serial Attached Small Computer System Interface (SAS) x8 
interface from the blade through an AirMax VS 3x6 connector, and will distribute to two SAS x4 
cables through SAS Mini-HD x4 side-by-side connectors, as shown in Figure 28. 
Tray BackplaneBlade1
Blade2
SAS
Airmax
VS2
SAS
Retimer SASx8
SAS[4:1]
SAS[8:5]
SAS
Airmax
VS2SAS
Retimer SASx8 SAS[4:1]
SAS[8:5]
  SAS
  MiniHD
  SAS
  Mini-HD
P1
P2
  SAS
  MiniHD
  SAS
  Mini-HD
P1
P2
 
Figure 28: SAS block diagram 
6.4 10 Gb/40Gb Ethernet 
The tray backplane will support a 10GbE and 40GbE ports from the blade through an AirMax VS2 
3x6 connector, and will distribute to a small form-factor pluggable (SFP+) and quad SFP+ (QSFP+) 
cable, as shown in Figure 29. This will include 3.3V power support for the enhanced SFP+/QSFP+ 
passive, active, or optical cables. The port2 SFP+ connectors will be a load option, and may not be 
loaded on all board revisions. 



 
32 October 30, 2014 
 
Blade1 Tray Backplane
Blade2
10GbE
Airmax
VS2
40GbE
10GbE
I2C
3.3 V
I2C
10GbE
Airmax
VS2
40GbE
10GbE
I2C
3.3 V
I2C
10GbE
40GbE
NIC
Mezz
Filter
Filter
QSFP+
SFP+
QSFP+
SFP+
P2
P1
P2
P1
10GbE
40GbE
NIC
Mezz
(optional)
(optional)
(optional)
Filter
Filter
 
Figure 29: Ethernet block diagram 
6.5 Tray Mezzanine Card 
The tray backplane will support two tray mezzanine cards, one per blade. Each tray mezzanine card 
supports a PCIe Gen3 x16 to a CPU on the blade. The PCIe interface includes four separate PCIe 
clocks, and resets to supports PCIe bifurcation of 1x4, 2x8, and 4x4. Bifurcation is communicated to 
the blade through CFG_ID signals. The tray mezzanine card is powered by 12V supplied by the 
blade, and will support a minimum supply current of 3A.  
Figure 3 shows a block diagram of the interface. 



Open Compute Project  Open CloudServer OCS Chassis 
http://opencompute.org 33 
 
Tray Backplane
Blade1
PCIe
Airmax
VS2
Tray
Mezz
Card
PCIe x16 Tx/RX
CLK_100Mhz[3:0]
CPU
Clock Gen
HSC
12V
Management
Circuitry
PCIE_RESET_N[3:0]
PCIE_WAKE_N
MEZZ_EN
PCIE_CFG_ID[1:0]
MEZZ_I2C
MEZZ_PRESENT_N
Blade1
PCIe
Airmax
VS2
Tray
Mezz
Card
PCIe x16 Tx/RX
CLK_100Mhz[3:0]
CPU
Clock Gen
HSC
12V
Management
Circuitry
PCIE_RESET_N[3:0]
PCIE_WAKE_N
MEZZ_EN
PCIE_CFG_ID[1:0]
MEZZ_I2C
MEZZ_PRESENT_N
PCIe x16 Tx/RX
CLK_100Mhz[3:0]
12V
PCIE_RESET_N[3:0]
PCIE_WAKE_N
MEZZ_EN
PCIE_CFG_ID[1:0]
MEZZ_I2C
MEZZ_PRESENT_N
PCIe x16 Tx/RX
CLK_100Mhz[3:0]
12V
PCIE_RESET_N[3:0]
PCIE_WAKE_N
MEZZ_EN
PCIE_CFG_ID[1:0]
MEZZ_I2C
MEZZ_PRESENT_N
 
Figure 30: Tray mezzanine card block diagram 
6.5.1 Chassis Management 
The tray backplane will distribute chassis management signals from the Chassis Manager to each of 
the blades. Figure 31 shows details of these signals.  



 
34 October 30, 2014 
 
Tray BackplaneBlade1
10GbE
AirMax
VS2
Edge
Finger
BLADE_B1_EN2
SERIAL_B1_RX1/TX1
SKU_B1_ID[2:0]
Blade
Management
Circuitry SERIAL_B1_RX2/TX2
BLADE_B1_EN1
BLADE_B2_EN1
SERIAL_B2_RX1/TX1
SERIAL_B2_RX2/TX2
PSU_B2_ALERT#
SAS
AirMax
VS2
SKU_B2_ID[2:0]
JBOD
Management
Circuitry
PCIe
AirMax
VS2
BLADE_EN1
SERIAl_RX1/TX1
SERIAl_RX1/TX1
SERIAL_RX2/TX2
BLADE_EN1
PSU_ALERT#
SKU_ID[2:0]
Blade2
10GbE
AirMax
VS2
Blade
Management
Circuitry
SAS
AirMax
VS2
JBOD
Management
Circuitry
PCIe
AirMax
VS2
BLADE_EN1
SERIAl_RX1/TX1
SERIAl_RX1/TX1
SERIAL_RX2/TX2
BLADE_EN1
PSU_ALERT#
SKU_ID[2:0]
 
Figure 31: Management block diagram 
6.5.2 Guide Pins 
The tray backplane will provide two guide pins for insertion and alignment of the blade to the tray 
backplane. The guide pins will be connected to GND on the tray backplane. The guide pins will be 
FCI MPN 10044366-101LF pins or equivalent. 
6.6 Connector Pinouts and Signal Descriptions 
The sections that follow detail the connector pinouts and signals. 



Open Compute Project  Open CloudServer OCS Chassis 
http://opencompute.org 35 
 
6.6.1 PDB 12V Power Connector 
The tray backplane will interface to the PDB through edge finger connections; these connections 
are designed to interface to an FCI MPN 10117936-003LF connector (or equivalent) on the PDB.  
This interface will provide for a minimum of 50A (600W) capacity on the 12V connections. 
Table 10 shows the pinout for the edge finger connector to the PDB. 
Table 10: PDB 12V power connector pinout 
Pin Signal name Pin Signal name 
P1 GND P5 GND 
P2 GND P6 GND 
P3 P12V P7 P12V 
P4 P12V P8 P12V 
Orientation key 
S1 SERIAL_B1_TXD1 S7 SERIAL_B2_TXD1 
S2 SERIAL_B1_RXD1 S8 SERIAL_B2_RXD1 
S3 BLADE_B1_EN1 S9 BLADE_B2_EN1 
S4 PSU_B1_ALERT_N S10 PSU_B2_ALERT_N 
S5 SERIAL_B1_TXD2 S11 SERIAL_B2_TXD2 
S6 SERIAL_B1_RXD2 S12 SERIAL_B2_RXD2 
Table 11 describes the signals for this interface. 
Table 11: PDB 12V power connector signal descriptions 
Signal name I/O Logic Description 
SERIAL_B1_TXD[2:1] I 3.3V Universal Asynchronous Receiver/Transmitter (UART) serial 
communication from the Chassis Manager to blade1 
SERIAL_B1_RXD[2:1] O 3.3V UART serial communication from blade 1 to the Chassis 
Manager 
BLADE_B1_EN1 I 3.3V Blade1 Enable from the Chassis Manager 
PSU_B1_ALERT_N I 3.3V Power supply alert from the Chassis Manager or PSU 
SERIAL_B2_TXD[2:1] I 3.3V UART serial communication from the Chassis Manager to 
blade 
SERIAL_B2_RXD[2:1] O 3.3V UART serial communication from the blade to the Chassis 
Manager 



 
36 October 30, 2014 
 
Signal name I/O Logic Description 
BLADE_B2_EN1 I 3.3V Blade2 Enable from the Chassis Manager 
PSU_B2_ALERT_N I 3.3V Power supply alert from the Chassis Manager or PSU 
P12V I 12V 12V power from PDB (PDU) 
6.6.2 Blade 12V Power Connector 
The tray backplane will distribute 12V power to each blade slot through an AirMax Power 2x2 FCI 
MPN 10052620-4555P00LF header receptacle connector (or equivalent). The connector will provide 
for a minimum of 40A (480W capacity) for each blade.  
Table 12 shows the pinout for the 12V power connector to the blade. Note that there are two of 
these connectors on the tray backplane, one for each blade. 
Table 12: Blade 12V power connector pinout 
Pin Signal name Description 
A1 GND  ----- 
A2 GND ----- 
A3 GND ----- 
A4 GND ----- 
A5 GND ----- 
A6 GND ----- 
B1 P12V 12V raw power to blade 
B2 P12V 12V raw power to blade 
B3 P12V 12V raw power to blade 
B4 P12V 12V raw power to blade 
B5 P12V 12V raw power to blade 
B6 P12V 12V raw power to blade 
C1 P12V 12V raw power to blade 
C2 P12V 12V raw power to blade 
C3 P12V 12V raw power to blade 
C4 P12V 12V raw power to blade 
C5 P12V 12V raw power to blade 
C6 P12V 12V raw power to blade 



Open Compute Project  Open CloudServer OCS Chassis 
http://opencompute.org 37 
 
Pin Signal name Description 
D1 GND ----- 
D2 GND ----- 
D3 GND ----- 
D4 GND ----- 
D5 GND ----- 
D6 GND ----- 
Figure 32 shows a front view of the header pins to the power connector.   
 
Figure 32: Front view of header pins 
Table 13 details the header pins and the current capacity. 
Table 13: AirMax Power connector header pinout 
Pin Signal name Capacity (in A) 
Position 1 12V return – first mate 20A 
Position 2 12V supply 20A 
Position 4 12V supply 20A 
Position 3 12V return 20A 
 
6.6.3 Blade SAS Interface 
The connector interfacing SAS from the blade to the tray backplane will be AirMax VS2 3x6, FCI 
MPN 10122643-101LF (or equivalent). Table 14 shows the pinout for the connector.  


 
38 October 30, 2014 
 
Note that only blade 1 is shown, but the pinouts for blade1 and blade 2 are identical. The 
designation _B1_ in the signal names indicates a connection to blade 1, and _B2_ indicates the 
connection to blade 2. 
Table 14: Blade SAS interface connector pinout 
 
Table 15 describes the signals for this interface. 
Table 15: SAS connector signal description 
Signal name I/O Logic Description 
SAS_B1_TX[8:1] I 
Current 
mode logic 
(CML) 
12Gb SAS Transmit from blade1 
SAS_B1_RX[8:1] O CML 12Gb SAS Receive to blade1 
BLADE_B1_EN1 O 3.3V Blade Enable from the Chassis Manager to blade 
For use by JBOD 
SERIAL_B1_TX1 O 3.3V Serial communication from the Chassis Manager to blade 
For use by JBOD 
SERIAL_B1_RX1 I 3.3V Serial communication from the blade to the Chassis Manager 
For use by JBOD 
JBOD_MATED_N O 3.3V Indicates to blade that the blade is mated to TBP 
6.6.4 Mini-SAS HD Connector 
The connector interfacing SAS from the tray backplane to SAS cables will be an SAS Mini-HD 1x2 
connector, FCI MPN 10112627-101LF. Table 16 shows the connector pinout for a single x4 Mini-HD 
SAS connector.  
Each connector supports a side-by-side cable (ports 1 and 2). There are two cable connections per 
tray backplane, one for each blade. Only blade 1 Port 1 is shown. Note that the designation _B1P1_ 
in the signal names indicates a connection to Blade1 Port1. 
GND GND GND J
SAS_B1_RX7N GND SAS_B1_RX5N GND SAS_B1_RX2N GND I
SAS_B1_RX7P SAS_B1_TX7N SAS_B1_RX5P SAS_B1_TX4N SAS_B1_RX2P SAS_B1_TX2N H
GND SAS_B1_TX7P GND SAS_B1_TX4P GND SAS_B1_TX2P G
SAS_B1_TX8N GND SAS_B1_TX5N GND SAS_B1_TX3N GND F
SAS_B1_TX8P SAS_B1_RX6N SAS_B1_TX5P SAS_B1_RX4N SAS_B1_TX3P SAS_B1_RX1N E
GND SAS_B1_RX6P GND SAS_B1_RX4P GND SAS_B1_RX1P D
SAS_B1_RX8N GND BLADE_B1_EN1 GND SAS_B1_RX3N GND C
SAS_B1_RX8P SAS_B1_TX6N JBOD_B1_MATED_N SERIAL_B1_RX1 SAS_B1_RX3P SAS_B1_TX1N B
GND SAS_B1_TX6P GND SERIAL_B1_TX1 GND SAS_B1_TX1P A
6 5 4 3 2 1



Open Compute Project  Open CloudServer OCS Chassis 
http://opencompute.org 39 
 
Table 16: Mini-SAS HD connector pinout 
Pin Signal name I/O Logic Description 
A1 RSVD N/A   NC (not supported by design) 
A2 INTL N/A   NC (not supported by design) 
A3 GND      
A4 SAS_B1P1_RX2P I CML SAS serial input from cable 
A5 SAS_B1P1_RX2N I CML SAS serial input from cable 
A6 GND      
A7 SAS_B1P1_RX4P I CML SAS serial input from cable 
A8 SAS_B1P1_RX4N I CML SAS serial input from cable 
A9 GND      
B1 VACT N/A   NC (not supported by design) 
B2 MODPRSL N/A   NC (not supported by design) 
B3 GND    
B4 SAS_B1P1_RX1P I CML SAS serial input from cable 
B5 SAS_B1P1_RX1N I CML SAS serial input from cable 
B6 GND    
B7 SAS_B1P1_RX3P I CML SAS serial input from cable 
B8 SAS_B1P1_RX3N I CML SAS serial input from cable 
B9 GND       
C1 SCL N/A   NC (not supported by design) 
C2 SDA N/A   NC (not supported by design) 
C3 GND    
C4 SAS_B1P1_TX2P O CML SAS serial output to cable 
C5 SAS_B1P1_TX2N O CML SAS serial output to cable 
C6 GND       
C7 SAS_B1P1_TX4P O CML SAS serial output to cable 
C8 SAS_B1P1_TX4N O CML SAS serial output to cable 
C9 GND       
D1 VACT N/A   NC (not supported by design) 
D2 VMON N/A   NC (not supported by design) 
D3 GND       



 
40 October 30, 2014 
 
Pin Signal name I/O Logic Description 
D4 SAS_B1P1_TX1P O CML SAS serial output to cable 
D5 SAS_B1P1_TX1N O CML SAS serial output to cable 
D6 GND       
D7 SAS_B1P1_TX3P O CML SAS serial output to cable 
D8 SAS_B1P1_TX3N O CML SAS serial output to cable 
D9 GND       
6.6.5 Blade 10Gb Ethernet Connector 
The connector interfacing the 10GbE from the blade to the tray backplane will be an AirMax VS2 
3x6 connector, FCI MPN 10122643-101LF (or equivalent).  
Table 17 shows the pinout for the 10GbE connector. Note that only blade1 is shown, but the 
pinouts for blade1 and blade2 are identical. The designation _B1 in the signal name indicates a 
connection to blade1. 
Table 17: Blade 10GbE connector pinout 
 
Table 18 describes the signals for this interface. 
Table 18: Blade 10GbE signal definitions 
Bus type I/O Logic Description 
ETH10G_B1_TX I CML 10GbE Transmit from Blade1 Port1 to SFP+ 
ETH10G_B1_RX O CML 10GbE Receive from Blade1 Port1 to SFP+ 
ETH10G_B1_SCL I 3.3V I2C Clock from the blade to SFP+ 
ETH10G_B1_SDA I/O 3.3V I2C Data from the blade to SFP+ 
GND GND GND J
ETH40G_B1_TX0N BLADE_MATED_B1_N SKU_B1_ID1 P3V3_B1_QSFP ETH10G_B1_PRES_N GND I
ETH40G_B1_TX0P ETH40G_B1_PRES_N SERIAL_B1_TX2 SERIAL_B1_TX1 BLADE_B1_EN1 ETH10G_B1_TXN H
GND PSU_B1_ALERT_N SERIAL_B1_RX2 SERIAL_B1_RX1 GND ETH10G_B1_TXP G
ETH40G_B1_RX0N GND ETH40G_B1_SCL SKU_B1_ID0 SKU_B1_ID2 GND F
ETH40G_B1_RX0P P3V3_B1_QSFP ETH40G_B1_SDA ETH10G_B1_SCL RSVD ETH10G_B1_RXN E
GND P3V3_B1_QSFP GND ETH10G_B1_SDA GND ETH10G_B1_RXP D
ETH40G_B1_TX1N GND ETH40G_B1_TX2N GND ETH40G_B1_RX3N GND C
ETH40G_B1_TX1P ETH40G_B1_RX1N ETH40G_B1_TX2P ETH40G_B1_RX2N ETH40G_B1_RX3P ETH40G_B1_TX3N B
GND ETH40G_B1_RX1P GND ETH40G_B1_RX2P GND ETH40G_B1_TX3P A
6 5 4 3 2 1



Open Compute Project  Open CloudServer OCS Chassis 
http://opencompute.org 41 
 
Bus type I/O Logic Description 
ETH10G_B1_PRES_N O 3.3V Indicates the presence of a 10GbE cable to the blade 
through MOD_ABS signal from SFP+ connector 
ETH40G_B1_TX[7:0] I CML 10GbE Transmit from Blade1 Port2 to QSFP+ 
ETH40G_B1_RX[7:0] O CML 10GbE Receive from Blade1 Port2 to QSFP+ 
ETH40G_B1_SCL I 3.3V I2C Clock from the blade to QSFP+ 
ETH40G_B1_SDA I/O 3.3V I2C Data from the blade to SFP+ 
ETH40G_B1_PRES_N O 3.3V 
Indicates the presence of a 10GbE cable through the Direct 
Attach Cable (DAC) PRESENT_N signal from the QSFP+ 
connector 
SKU_B1_ID<2:0> O 3.3V ID signal indicating the SKU of the tray backplane 
Each should be tied to GND through a 0 ohm resistor 
P3V3_B1_QSFP I 3.3V 3.3V SFP+ connector I2C device power 
BLADE_B1_MATED_N O 3.3V 
Indicates to the blade that the blade and tray backplane are 
mated 
Should be tied to GND on the tray backplane   
SERIAL_B1_RX[2:1] I 3.3V 
UART serial communication from the blade to the Chassis 
Manager 
Two nodes per blade. 
SERIAL_B1_TX[2:1] O 3.3V 
UART serial communication from the Chassis Manager to 
the blade 
Two nodes per blade  
BLADE_B1_EN1 O 3.3V Node/Blade Enable signal from the Chassis Manager to the 
blade 
PSU_B1_ALERT_N O 3.3V Power supply alert signal from the Chassis Manager or PSU 
MEZZ_B1_PRESENT_N O 3.3V Indicates to the blade that a tray mezzanine card is installed 
Signal is tied to GND on the tray mezzanine card 
MEZZ_B1_EN I 3.3V 3.3V Power Enable for the tray mezzanine card 
Ground  0V Ground pins 
6.6.6 10GbE SFP+ Connector 
The connector interfacing 10GbE from the tray backplane to the Ethernet cables will be an SFP+ 
connector, FCI MPN 10099099-111LF (or equivalent). The connector shall be supported by a SFP+ 
connector cage, FCI MPN 10099100-011LF (or equivalent). The connector cage must not include a 
heat sink. 



 
42 October 30, 2014 
 
Table 19 shows the standard pinout for the SFP+ connector. The design supports Direct Attach 
Cable (DAC) and does not support active cables. 
Table 19: 10GbE SFP+ connector pinout 
Pin Signal name I/O Logic Description 
1 VEET     Module transmitter ground 
2 TX_FAULT O LVTTL Module transmitter fault (not used) 
Low voltage transistor-transistor logic (LVTTL) 
3 TX_DISABLE I LVTTL Transmitter disable (not used) 
4 SDA I/O LVTTL I2C data 
5 SCL I LVTTL I2C clock 
6 MOD_ABS O   Module absent 
Connected to GND in the module 
7 RS0 I LVTTL Rate select 0 (not used) 
8 RX_LOS O LVTTL Receiver loss of signal (not used) 
9 RS1 I LVTTL Rate select 1 (not used) 
10 VEER     Module receiver ground 
11 VEER     Module receiver ground 
12 RD_N O CML Receiver non-inverted data output 
13 RD_P O CML Receiver inverted data output 
14 VEER     Module receiver ground 
15 VCCR     Module receiver 3.3V supply 
16 VCCT     Module transmitter 3.3V supply 
17 VEET     Module transmitter ground 
18 TD_P I CML Transmitter non-inverted data input 
19 TD_N I CML Transmitter inverted data input 
20 VEET     Module transmitter ground 
6.6.7 40GbE QSFP+ Connector 
The connector interfacing 40GbE from the tray backplane to Ethernet cables will be a QSFP+ 
connector, FCI MPN 10099113-102LF (or equivalent). The connector will be supported by a QSFP+ 
connector cage, FCI MPN 10099114-001LF (or equivalent). The connector cage must not include a 
heat sink.  



Open Compute Project  Open CloudServer OCS Chassis 
http://opencompute.org 43 
 
Table 20 shows the standard pinout for the QSFP+ connector. The design supports DAC  only, and 
does not support active cables. 
Table 20: 40GbE QSFP+ connector pinout 
Pin Signal name I/O Logic Description 
1 GND     Ground 
2 ETH40G_B1_TX2P O CML 10G data output to cable 
3 ETH40G_B1_TX2P O CML 10G data output to cable 
4 GND     Ground 
5 ETH40G_B1_TX4N O CML 10G data output to cable 
6 ETH40G_B1_TX4P O CML 10G data output to cable 
7 GND     Ground 
8 ModSelL O LVTTL Module select (not used) 
9 ResetL O LVTTL Module reset (not used) 
10 VccRx O   +3.3V power supply receiver 
11 SCL I/O LVCMOS 2-wire serial interface clock 
12 SDA I/O LVCMOS 2-wire serial interface data 
13 GND     Ground 
14 ETH40G_B1_RX3P I CML 10G data input from cable 
15 ETH40G_B1_RX3N I CML 10G data input from cable 
16 GND     Ground 
17 ETH40G_B1_RX1P I CML 10G data input from cable 
18 ETH40G_B1_RX1N I CML 10G data input from cable 
19 GND     Ground 
20 GND     Ground 
13 RD_P O CML Receiver inverted data output 
14 VEER     Module receiver ground 
15 VCCR     Module receiver 3.3V supply 
16 VCCT     Module transmitter 3.3V supply 
17 VEET     Module transmitter ground 
18 TD_P I CML Transmitter non-inverted data input 
19 TD_N I CML Transmitter inverted data input 
20 VEET     Module transmitter ground 



 
44 October 30, 2014 
 
Pin Signal name I/O Logic Description 
21 ETH40G_B1_RX2N I CML 10G data input from cable 
22 ETH40G_B1_RX2P I CML 10G data input from cable 
23 GND     Ground 
24 ETH40G_B1_RX4N I CML 10G data input from cable 
25 ETH40G_B1_RX4P I CML 10G data input from cable 
26 GND     Ground 
27 ModPrsL I LVTTL Module present 
Connected to GND in the module 
28 IntL I LVTTL Interrupt (not used) 
29 VccTx O   +3.3V power supply transmitter 
30 Vcc1 O   +3.3V power supply 
31 LPMode O LVTTL Low power mode (not used) 
32 GND     Ground 
33 ETH40G_B1_TX3P O CML 10G data output to cable 
34 ETH40G_BLADE1_TX3N O CML 10G data output to cable 
35 GND     Ground 
36 ETH40G_B1_TX1P O CML 10G data output to cable 
37 ETH40G_B1_TX1N O CML 10G data output to cable 
38 GND     Ground 
6.6.8 Blade PCIe Gen3 Connector 
The tray backplane will interface PCIe Gen3 to the blade through an AirMax VS2 5x10 connector FCI 
connector, MPN 10122665-101LF (or equivalent).  
Table 21 shows the pinout for the connector. Note that only blade1 is shown, but the pinout for 
blade1 and blade2 are identical. The designation _B1_ in the signal names indicates a connection to 
blade1; _B2_ is used for the connection to blade2.



 
http://opencompute.org 45 
 
Table 21. PCIe interface connector pinout 
 
Table 22 describes the signals for this interface. 
GND GND GND GND GND P
P12V_MEZZ GND PCIE_B2T_TX_DN<8> GND PCIE_B2T_TX_DN<10> GND PCIE_B2T_TX_DN<12> GND PCIE_B2T_TX_DN<14> GND O
P12V_MEZZ GND PCIE_B2T_TX_DP<8> PCIE_B2T_TX_DN<9> PCIE_B2T_TX_DP<10> PCIE_B2T_TX_DN<11> PCIE_B2T_TX_DP<12> PCIE_B2T_TX_DN<13> PCIE_B2T_TX_DP<14> PCIE_B2T_TX_DN<15> N
GND GND GND PCIE_B2T_TX_DP<9> GND PCIE_B2T_TX_DP<11> GND PCIE_B2T_TX_DP<13> GND PCIE_B2T_TX_DP<15> M
P12V_MEZZ GND PCIE_B2T_TX_DN<0> GND PCIE_B2T_TX_DN<2> GND PCIE_B2T_TX_DN<4> GND PCIE_B2T_TX_DN<6> GND L
P12V_MEZZ CLK_100M_N<3> PCIE_B2T_TX_DP<0> PCIE_B2T_TX_DN<1> PCIE_B2T_TX_DP<2> PCIE_B2T_TX_DN<3> PCIE_B2T_TX_DP<4> PCIE_B2T_TX_DN<5> PCIE_B2T_TX_DP<6> PCIE_B2T_TX_DN<7> K
P12V_MEZZ CLK_100M_P<3> GND PCIE_B2T_TX_DP<1> GND PCIE_B2T_TX_DP<3> GND PCIE_B2T_TX_DP<5> GND PCIE_B2T_TX_DP<7> J
P12V_MEZZ GND SERIAL_RX2 GND BLADE_MATED_N GND MEZZ_SDA GND PCIE_RESET_N<0> GND I
GND CLK_100M_N<2> SERIAL_TX2 PSU_ALERT_N MEZZ_PRESENT_N MEZZ_EN PCIE_WAKE_N PCIE_CFG_ID1 PCIE_RESET_N<1> PCIE_RESET_N<2> H
GND CLK_100M_P<2> GND RSVD GND MEZZ_SCL GND PCIE_CFG_ID0 GND PCIE_RESET_N<3> G
GND GND PCIE_T2B_RX_DN<8> GND PCIE_T2B_RX_DN<10> GND PCIE_T2B_RX_DN<12> GND PCIE_T2B_RX_DN<14> GND F
P5V_USB CLK_100M_N<1> PCIE_T2B_RX_DP<8> PCIE_T2B_RX_DN<9> PCIE_T2B_RX_DP<10> PCIE_T2B_RX_DN<11> PCIE_T2B_RX_DP<12> PCIE_T2B_RX_DN<13> PCIE_T2B_RX_DP<14> PCIE_T2B_RX_DN<15> E
GND CLK_100M__B1<1> GND PCIE_T2B_RX_DP<9> GND PCIE_T2B_RX_DP<11> GND PCIE_T2B_RX_DP<13> GND PCIE_T2B_RX_DP<15> D
USB- GND PCIE_T2B_RX_DN<0> GND PCIE_T2B_RX_DN<2> GND PCIE_T2B_RX_DN<4> GND PCIE_T2B_RX_DN<6> GND C
USB+ CLK_100M_N<0> PCIE_T2B_RX_DP<0> PCIE_T2B_RX_DN<1> PCIE_T2B_RX_DP<2> PCIE_T2B_RX_DN<3> PCIE_T2B_RX_DP<4> PCIE_T2B_RX_DN<5> PCIE_T2B_RX_DP<6> PCIE_T2B_RX_DN<7> B
GND CLK_100M_P<0> GND PCIE_T2B_RX_DP<1> GND PCIE_T2B_RX_DP<3> GND PCIE_T2B_RX_DP<5> GND PCIE_T2B_RX_DP<7> A
10 9 8 7 6 5 4 3 2 1



 
46 September 6, 2014 
Table 22: PCIe Gen3 connector signal definitions 
Bus type I/O Logic Description 
PCIE_B2T_B1_TX_DP/N[15:0] I CML PCIe Gen3 Transmit from the blade to the tray 
mezzanine card through the tray backplane 
PCIE_T2B_B1_RX_DP/N[15:0] O CML PCIe Gen3 Receive from the tray mezzanine card to the 
blade through the tray backplane 
CLK_100M_B1_P/N[3:0] I CML PCIe Gen3 Clock from the blade to the tray mezzanine 
card through the tray backplane 
PCIE_RESET_B1_N[3:0] I 3.3V PCIe Reset from the blade to the tray mezzanine card 
through the tray backplane 
PCIE_WAKE_B1_N I 3.3V PCIe Wake from the blade to the tray mezzanine card 
through the tray backplane 
PCIE_CFG_B1_ID[1:0] O 3.3V 
PCIE Configuration ID bits 
3.3V pullup on tray mezzanine card 
Should be connected to GPIO on the PCH 
00 = 1 x 16 bifurcation 
01 = 2 x 8 bifurcation 
10 = 4 x 4 bifurcation 
11 = N/A 
MEZZ_B1_SDA O 3.3V I2C Data from the blade to the tray mezzanine card 
through the tray backplane 
MEZZ_B1_SCL I 3.3V I2C Clock from the blade to the tray mezzanine card 
through the tray backplane 
MEZZ_PRESENT_B1_N O 3.3V 
Present signal from the tray mezzanine card to the blade 
through tray backplane 
Signal is grounded on the tray mezzanine card 
MEZZ_B1_EN   3.3V Power Enable from the blade to tray mezzanine 
card through the tray backplane 
BLADE_MATED_N O 3.3V 
Indicates to the blade that the blade and tray backplane 
are mated 
Should be tied to GND on tray backplane 
USB+ I CML USB 2.0 from the blade 
USB- I CML USB 2.0 from the blade 
P5V_USB I 5V 5V USB power 
P12_B1_MEZZ I 12V 
12V power from the blade to tray mezzanine card 
through tray backplane 
Maximum power is 36W 



Open Compute Project  Open CloudServer OCS Chassis 
http://opencompute.org 47 
 
Bus type I/O Logic Description 
SERIAL_B1_RX2 I 3.3V UART serial communication from the blade to the 
Chassis Manager 
SERIAL_B1_TX2 O 3.3V UART serial communication from the Chassis Manager to 
the blade 
PSU_B1_ALERT_N O 3.3V Power supply alert signal from the Chassis Manager or 
PSU 
Ground  0V Ground pins 
6.6.9 Tray Mezzanine Card Connector 
The tray backplane will interface PCIe Gen3 to the tray mezzanine card through a Samtec SEARAY 
connector, MPN SEAF-20-06.5-L-08-2-A-LP-K-TR or equivalent.  
Table 23 shows the pinout for the tray mezzanine card connector. Note that only blade1 is shown, 
but the pinouts for blade1 and blade2 are identical. The designation _B1_ in the signal names 
indicates a connection to blade1, and the designation _B1_ is used for the connection to blade2.



 
48 September 6, 2014 
Table 23: Tray mezzanine card connector pinout  
 
Table 24 describes  the signals for this interface. 
 
 
153 P12V_B1_MEZZ P12_B1_MEZZ P12_B1_MEZZ MEZZ_B1_SCL MEZZ_B1_EN MEZZ_B1_SDA PCIE_WAKE_B1_N MEZZ_PRESENT_B1_N 160
145 P12V_B1_MEZZ GND GND PCIE_CFG_B1_ID1 PCIE_CFG_B1_ID0 PCIE_RESET_B1_N<0> PCIE_RESET_B1_N<1> PCIE_RESET_B1_N<3> 152
137 P12V_B1_MEZZ CLK_100M_B1_N<0> GND CLK_100M_B1_N<1> GND CLK_100M_B1_N<2> PCIE_RESET_B1_N<2> CLK_100M_B1_N<3> 144
129 GND CLK_100M_B1_P<0> GND CLK_100M_B1_P<1> GND CLK_100M_B1_P<2> GND CLK_100M_B1_P<3> 136
121 PCIE_T2B_B1_RX_DN<0> GND PCIE_T2B_B1_RX_DN<8> GND PCIE_B2T_B1_TX_DN<0> GND PCIE_B2T_B1_TX_DN<8> GND 128
113 PCIE_T2B_B1_RX_DP<0> GND PCIE_T2B_B1_RX_DP<8> GND PCIE_B2T_B1_TX_DP<0> GND PCIE_B2T_B1_TX_DP<8> GND 120
105 GND PCIE_T2B_B1_RX_DN<1> GND PCIE_T2B_B1_RX_DN<9> GND PCIE_B2T_B1_TX_DN<1> GND PCIE_B2T_B1_TX_DN<9> 112
97 GND PCIE_T2B_B1_RX_DP<1> GND PCIE_T2B_B1_RX_DP<9> GND PCIE_B2T_B1_TX_DP<1> GND PCIE_B2T_B1_TX_DP<9> 104
89 PCIE_T2B_B1_RX_DN<2> GND PCIE_T2B_B1_RX_DN<10> GND PCIE_B2T_B1_TX_DN<2> GND PCIE_B2T_B1_TX_DN<10> GND 96
81 PCIE_T2B_B1_RX_DP<2> GND PCIE_T2B_B1_RX_DP<10> GND PCIE_B2T_B1_TX_DP<2> GND PCIE_B2T_B1_TX_DP<10> GND 88
73 GND PCIE_T2B_B1_RX_DN<3> GND PCIE_T2B_B1_RX_DN<11> GND PCIE_B2T_B1_TX_DN<3> GND PCIE_B2T_B1_TX_DN<11> 80
65 GND PCIE_T2B_B1_RX_DP<3> GND PCIE_T2B_B1_RX_DP<11> GND PCIE_B2T_B1_TX_DP<3> GND PCIE_B2T_B1_TX_DP<11> 72
57 PCIE_T2B_B1_RX_DN<4> GND PCIE_T2B_B1_RX_DN<12> GND PCIE_B2T_B1_TX_DN<4> GND PCIE_B2T_B1_TX_DN<12> GND 64
49 PCIE_T2B_B1_RX_DP<4> GND PCIE_T2B_B1_RX_DP<12> GND PCIE_B2T_B1_TX_DP<4> GND PCIE_B2T_B1_TX_DP<12> GND 56
41 GND PCIE_T2B_B1_RX_DN<5> GND PCIE_T2B_B1_RX_DN<13> GND PCIE_B2T_B1_TX_DN<5> GND PCIE_B2T_B1_TX_DN<13> 48
33 GND PCIE_T2B_B1_RX_DP<5> GND PCIE_T2B_B1_RX_DP<13> GND PCIE_B2T_B1_TX_DP<5> GND PCIE_B2T_B1_TX_DP<13> 40
25 PCIE_T2B_B1_RX_DN<6> GND PCIE_T2B_B1_RX_DN<14> GND PCIE_B2T_B1_TX_DN<6> GND PCIE_B2T_B1_TX_DN<14> GND 32
17 PCIE_T2B_B1_RX_DP<6> GND PCIE_T2B_B1_RX_DP<14> GND PCIE_B2T_B1_TX_DP<6> GND PCIE_B2T_B1_TX_DP<14> GND 24
9 GND PCIE_T2B_B1_RX_DN<7> GND PCIE_T2B_B1_RX_DN<15> GND PCIE_B2T_B1_TX_DN<7> GND PCIE_B2T_B1_TX_DN<15> 16
1 GND PCIE_T2B_B1_RX_DP<7> GND PCIE_T2B_B1_RX_DP<15> GND PCIE_B2T_B1_TX_DP<7> GND PCIE_B2T_B1_TX_DP<15> 8



 
http://opencompute.org 49 
Table 24: Tray mezzanine card signal definitions 
Signal name I/O Logic Description 
PCIE_B2T_B1_TX_DP/N[15:0] OI CML PCIe Gen3 Transmit from the blade to thet ray 
mezzanine card through the tray backplane 
PCIE_B2T_B1_RX_DP/N[15:0] I CML PCIe Gen3 Receive from the tray mezzanine card to the 
blade through the tray backplane 
CLK_100M_B1_P/N[3:0] O CML PCIe Gen3 Clock from the blade to the tray mezzanine 
card through the tray backplane 
PCIE_RESET_B1_N[3:0] O 3.3V PCIe Reset from the blade to the tray mezzanine card 
through the tray backplane 
PCIE_WAKE_B1_N O 3.3V PCIe Wake from the blade to the tray mezzanine card 
through the tray backplane  
PCIE_CFG_B1_ID[1:0] I 3.3V 
PCIE Configuration ID bits 
3.3V Pullup on the tray mezzanine card   
 00 = 1 x16 bifurcation 
 01 = 2 x8 bifurcation 
 10 = 4 x4 bifurcation 
 11 = N/A 
MEZZ_B1_EN O 3.3V 3.3V Power Enable from the blade to the tray mezzanine 
card through the tray backplane 
MEZZ_PRESENT_B1_N I 3.3V 
Present signal from the tray mezzanine card to the blade 
through the tray backplane 
Signal is grounded on the tray mezzanine card 
MEZZ_B1_SCL O 3.3V I2C Clock from the blade to the tray mezzanine card 
through the tray backplane 
MEZZ_B1_SDA I/O 3.3V I2C Data from the blade to the tray mezzanine card 
through the tray backplane 
P12_B1_MEZZ O 12V 
12V Power from the blade to the tray mezzanine card 
through the tray backplane 
Maximum power is 36W 
GND  0V Ground pins 
6.7 12V Power Cable 
The tray backplane will provide a four-pin mini-fit connector for cabling 12V to an external 
assembly or cabling 12V as an input for benchtop testing.  The connector will be a Molex MiniFit Jr 
90120-0123 (or equivalent). 



 
50 October 30, 2014 
 
6.8 USB Cable 
The tray backplane will support a four-pin connector for cabling USB to the tray mezzanine card.  
The connector will be a Tyco Electronics (TE) 440054-4 card (or equivalent).  
Table 25 shows the pinout. Note that only blade1 is shown, but the pinouts for blade1 and blade2 
are identical. The designation _B1_ in the signal names indicates a connection to blade1, and the 
designation _B2_ is used for the connection to blade2. 
Table 25: USB pinout 
Pin Signal name I/O Logic Description 
1 GND     Ground 
2 USB_B1_P O CML USB 
3 USB_B1_N O CML USB 
4 P5_B1_USB     5V (500mA max) 
 
6.9 Connector Part Number Summary 
Table 26 summarizes the connector part numbers. 
Table 26: Summary of connector part numbers 
Quantity Assembly 
attachment Description MPN 
1 PDB Edgefinger designed to interface to FCI 
MPN (FCI) 10117936-003LF N/A 
4 Blade 
motherboard 
AirMax VS2 receptacle   
(3 pair, 6 column, 54 contact, 2mm 
spacing, press fit) 
(FCI) 10122643-101LF  
(or equivalent) 
2 Blade 
motherboard 
AirMax VS2 receptacle 
(5 pair, 10 column, 150 contact, 2mm 
spacing, press fit) 
(FCI) 10122665-101LF  
(or equivalent) 
2 Blade 
motherboard AirMax Power receptacle, R/A,  2x2 (FCI) 10052620-4555P00LF (or 
equivalent) 
4 Blade 
motherboard Guide pin— 10.8mm, right angle 0° key (FCI) 10044366-101LF  
(or equivalent) 



Open Compute Project  Open CloudServer OCS Chassis 
http://opencompute.org 51 
 
Quantity Assembly 
attachment Description MPN 
2 Tray mezzanine 
card 
Samtec SEARAY SEAF open pin field array,  
8x20 BGA  
(Samtec) SEAF-20-06.0-S-08-2-
A-K-TR 
(or equivalent) 
2 SAS cable SAS Mini HD Assembly 1x2 (FCI) 10112627-101LF  
(or equivalent) 
2 10GbE cable SFP+ connector and cage 
(FCI) 10099099-111LF 
(connector) 
(FCI) 10099100_011LF (cage) 
(or equivalent) 
2 40GbE cable QSFP+ connector and cage 
(FCI) 10099113-102LF 
(connector) 
(FCI) 10116015-001LF (cage) 
(or equivalent) 
1 Tray mezzanine 
card USB cable connector (Tyco Electronics) 440054-4  
(or equivalent) 
1 12V cable 12V power cable connector (Molex) 90120-0123  
(or equivalent) 
6.10 Board Stackup 
Table 27 details the recommended layer stack-up for the tray backplane. Note that the board has 
the following notable design features and constraints: 
 8-layer hi-temp EM888 (or equivalent) assembly 
 0.062 +/-10% targeted thickness 
 Signal layers and corresponding ground planes are etched from 1.0 ounce copper planes 
 Power layers are etched from 2.0 ounce copper planes 
 Plating Organic Solderability Preservative (OSP) 
 Top and bottom layers will have both silkscreen and solder mask 
Table 27: Recommended stackup for tray backplane 
Layer Plane description Layer thickness 
(mil) 
Copper weight 
(oz) 
 Solder mask  0.5  
Signal 1 SIGNAL 1.9 1.5 
 Prepreg 2.7  



 
52 October 30, 2014 
 
Layer Plane description Layer thickness 
(mil) 
Copper weight 
(oz) 
Plane 2 GND 1.3 1 
 Core 4  
Signal 3 SIGNAL 1.3 1 
 Prepreg 15  
Plane 4 POWER 2.6 2 
 Core 4  
Plane 5 POWER 2.6 2 
 Prepreg 15  
Signal 6 SIGNAL 1.3 1 
 Core 4  
Plane 7 GND 1.3 1 
 Prepreg 2.7  
Signal 8 SIGNAL 1.9 1.5 
 Solder mask 0.5  
Total 62.6 +8 / -5 
Table 28 details the required impedance and recommended trace widths for the signal types 
used on the PCB.  Actual trace widths may vary slightly depending on the final vendor solution.  
Note that a high-speed signal topology should support an insertion loss of < 0.7db/inch. 
Table 28: Required impedance and recommended trace widths 
Outer layers 
Trace width Impedance Variation Signals 
4 50 ohms 15%  All single-ended signals 
Trace width/spacing Impedance Variation Signals 
8/4 85 ohms diff 17.50% PCIe, PCIe Clocks 
7/5 100 ohms diff 17.50% 10GbE, SAS 
Inner layers 
Trace Width Impedance Variation Signals 
4.5 mils 50 10% All single-ended signals 



Open Compute Project  Open CloudServer OCS Chassis 
http://opencompute.org 53 
 
Trace Width/Spacing Impedance Variation Signals 
6.5/5.0 85 ohms diff 12% PCIe, PCIe Clocks 
8.8/4.2 100 ohms diff 12% 10GbE, SAS 
6.11 Tray Backplane Electrical Specifications 
The following sections provide specifications for the blade input voltage and current, as well as 
the primary blade signals. 
6.11.1 Input Voltage, Power, and Current 
Table 29 lists the input voltage and current requirements for the 12V supply from the PDB. The 
maximum current is based on the maximum current for the power connectors to the blade. The 
maximum and minimum voltages include the effects of connector temperature, age, 
noise/ripple, and dynamic loading. 
Table 29: Input voltage and current from the PDB 
Nominal voltage Min voltage Max voltage Max current 
12.3V DC 11V DC 14V DC 72A 
Table 30 lists the output voltage and current requirements for 12V supply to each of the blades. 
The maximum current is based on the current capacity of the power connectors to the blades. 
Table 30: Output voltage and current to blades 
Nominal voltage Min voltage Max voltage Max current 
12.3V DC 11V DC 14V DC 36A 
Table 31 lists the voltage and current requirement for the 12V supply from the blade to the tray 
mezzanine card. The maximum current is based on the current capacity for supporting a 36W 
mezzanine card. 
Table 31: Input voltage and current from blade to tray mezzanine card 
Nominal voltage Min voltage Max voltage Max current 
12.3V DC 11V DC 14V DC 3A 



 
54 October 30, 2014 
 
6.11.2 Grounding and Return 
The tray backplane grounding/return is provided by the assembly guide pin. The logic return, or 
12V bus return, is provided through the 12V power connectors and signal connectors. 
6.12 Component and Hole Locations 
Figure 33 details the component and hole locations for the tray backplane . The view is from the 
bottom side of the PCB assembly. 
 
Figure 33: Component and hole locations 
